(kicad_pcb
	(version 20240108)
	(generator "pcbnew")
	(generator_version "8.0")
	(general
		(thickness 1.62)
		(legacy_teardrops no)
	)
	(paper "A4")
	(title_block
		(title "Jetson Orin Baseboard")
		(date "2025-03-12")
		(rev "1.3.4")
		(company "Antmicro Ltd")
		(comment 1 "www.antmicro.com")
		(comment 9 "footprints 326-330 of 677")
	)
	(layers
		(0 "F.Cu" signal)
		(1 "In1.Cu" signal)
		(2 "In2.Cu" signal)
		(3 "In3.Cu" signal)
		(4 "In4.Cu" jumper)
		(5 "In5.Cu" signal)
		(6 "In6.Cu" signal)
		(31 "B.Cu" signal)
		(32 "B.Adhes" user "B.Adhesive")
		(33 "F.Adhes" user "F.Adhesive")
		(34 "B.Paste" user)
		(35 "F.Paste" user)
		(36 "B.SilkS" user "B.Silkscreen")
		(37 "F.SilkS" user "F.Silkscreen")
		(38 "B.Mask" user)
		(39 "F.Mask" user)
		(40 "Dwgs.User" user "User.Drawings")
		(41 "Cmts.User" user "User.Comments")
		(42 "Eco1.User" user "User.Eco1")
		(43 "Eco2.User" user "User.Eco2")
		(44 "Edge.Cuts" user)
		(45 "Margin" user)
		(46 "B.CrtYd" user "B.Courtyard")
		(47 "F.CrtYd" user "F.Courtyard")
		(48 "B.Fab" user)
		(49 "F.Fab" user)
	)
	(footprint "antmicro-footprints:R_0402_1005Metric"
		(layer "B.Cu")
		(at 108.15 106.9)
		(descr "Resistor SMD 0402")
		(tags "resistor SMD 0402")
		(property "Reference" "R23"
			(at -0.88 0.42 180)
			(layer "B.SilkS")
			(effects
				(font
					(size 0.7 0.7)
					(thickness 0.15)
				)
				(justify left bottom mirror)
			)
		)
		(property "Value" "R_0R_0402"
			(at 0 -1.4 180)
			(layer "B.Fab")
			(effects
				(font
					(size 0.7 0.7)
					(thickness 0.15)
				)
				(justify left bottom mirror)
			)
		)
		(property "Footprint" "antmicro-footprints:R_0402_1005Metric"
			(at 0 0 0)
			(layer "F.Fab")
			(hide yes)
			(effects
				(font
					(size 1.27 1.27)
					(thickness 0.15)
				)
			)
		)
		(property "Datasheet" "https://industrial.panasonic.com/cdbs/www-data/pdf/RDA0000/AOA0000C301.pdf"
			(at 0 0 0)
			(layer "F.Fab")
			(hide yes)
			(effects
				(font
					(size 1.27 1.27)
					(thickness 0.15)
				)
			)
		)
		(property "Author" "Antmicro"
			(at 0 0 0)
			(layer "B.Fab")
			(hide yes)
			(effects
				(font
					(size 1 1)
					(thickness 0.15)
				)
				(justify mirror)
			)
		)
		(property "Current" "1A"
			(at 0 0 0)
			(layer "B.Fab")
			(hide yes)
			(effects
				(font
					(size 1 1)
					(thickness 0.15)
				)
				(justify mirror)
			)
		)
		(property "License" "Apache-2.0"
			(at 0 0 0)
			(layer "B.Fab")
			(hide yes)
			(effects
				(font
					(size 1 1)
					(thickness 0.15)
				)
				(justify mirror)
			)
		)
		(property "MPN" "ERJ2GE0R00X"
			(at 0 0 0)
			(layer "B.Fab")
			(hide yes)
			(effects
				(font
					(size 1 1)
					(thickness 0.15)
				)
				(justify mirror)
			)
		)
		(property "Manufacturer" "Panasonic"
			(at 0 0 0)
			(layer "B.Fab")
			(hide yes)
			(effects
				(font
					(size 1 1)
					(thickness 0.15)
				)
				(justify mirror)
			)
		)
		(property "Tolerance" ""
			(at 0 0 0)
			(layer "B.Fab")
			(hide yes)
			(effects
				(font
					(size 1 1)
					(thickness 0.15)
				)
				(justify mirror)
			)
		)
		(property "Val" "0R"
			(at 0 0 0)
			(layer "B.Fab")
			(hide yes)
			(effects
				(font
					(size 1 1)
					(thickness 0.15)
				)
				(justify mirror)
			)
		)
		(sheetname "USB3")
		(sheetfile "usb3.kicad_sch")
		(attr smd exclude_from_pos_files exclude_from_bom dnp)
		(fp_rect
			(start -0.925 0.47)
			(end 0.925 -0.47)
			(stroke
				(width 0.05)
				(type default)
			)
			(fill none)
			(layer "B.CrtYd")
		)
		(fp_rect
			(start -0.5 0.25)
			(end 0.5 -0.25)
			(stroke
				(width 0.15)
				(type solid)
			)
			(fill none)
			(layer "B.Fab")
		)
		(fp_text user "${REFERENCE}"
			(at -0.95 -3.168 180)
			(layer "B.Fab")
			(hide yes)
			(effects
				(font
					(size 0.7 0.7)
					(thickness 0.15)
				)
				(justify left bottom mirror)
			)
		)
		(fp_text user "Author: Antmicro"
			(at -0.95 -4.169 180)
			(layer "B.Fab")
			(hide yes)
			(effects
				(font
					(size 0.7 0.7)
					(thickness 0.15)
				)
				(justify left bottom mirror)
			)
		)
		(fp_text user "License: Apache-2.0"
			(at -0.95 -5.169 180)
			(layer "B.Fab")
			(hide yes)
			(effects
				(font
					(size 0.7 0.7)
					(thickness 0.15)
				)
				(justify left bottom mirror)
			)
		)
		(pad "1" smd roundrect
			(at -0.48 0)
			(size 0.59 0.64)
			(layers "B.Cu" "B.Paste" "B.Mask")
			(roundrect_rratio 0.25)
			(net 284 "/USB3/USBC1_ID")
			(pintype "passive")
		)
		(pad "2" smd roundrect
			(at 0.48 0)
			(size 0.59 0.64)
			(layers "B.Cu" "B.Paste" "B.Mask")
			(roundrect_rratio 0.25)
			(net 116 "USB_FLASH_ID")
			(pintype "passive")
		)
	)
	(footprint "antmicro-footprints:XDFN-2_1x0.60mm"
		(layer "B.Cu")
		(at 126.25 127.15)
		(property "Reference" "D59"
			(at -1.35 -0.6 180)
			(layer "B.SilkS")
			(effects
				(font
					(size 0.7 0.7)
					(thickness 0.15)
				)
				(justify right bottom mirror)
			)
		)
		(property "Value" "TPD1E0B04_XDFN-2"
			(at 0 -1.5 180)
			(layer "B.Fab")
			(effects
				(font
					(size 0.7 0.7)
					(thickness 0.15)
				)
				(justify left bottom mirror)
			)
		)
		(property "Footprint" "antmicro-footprints:XDFN-2_1x0.60mm"
			(at 0 0 0)
			(layer "F.Fab")
			(hide yes)
			(effects
				(font
					(size 1.27 1.27)
					(thickness 0.15)
				)
			)
		)
		(property "Datasheet" "https://www.ti.com/general/docs/suppproductinfo.tsp?distId=26&gotoUrl=https://www.ti.com/lit/gpn/tpd1e0b04"
			(at 0 0 0)
			(layer "F.Fab")
			(hide yes)
			(effects
				(font
					(size 1.27 1.27)
					(thickness 0.15)
				)
			)
		)
		(property "MPN" "TPD1E0B04DPYR"
			(at 0 0 0)
			(layer "B.Fab")
			(hide yes)
			(effects
				(font
					(size 1 1)
					(thickness 0.15)
				)
				(justify mirror)
			)
		)
		(property "Manufacturer" "Texas Instruments"
			(at 0 0 0)
			(layer "B.Fab")
			(hide yes)
			(effects
				(font
					(size 1 1)
					(thickness 0.15)
				)
				(justify mirror)
			)
		)
		(property "Author" "Antmicro"
			(at 0 0 0)
			(layer "B.Fab")
			(hide yes)
			(effects
				(font
					(size 1 1)
					(thickness 0.15)
				)
				(justify mirror)
			)
		)
		(property "License" "Apache-2.0"
			(at 0 0 0)
			(layer "B.Fab")
			(hide yes)
			(effects
				(font
					(size 1 1)
					(thickness 0.15)
				)
				(justify mirror)
			)
		)
		(sheetname "Peripherals")
		(sheetfile "peripherals.kicad_sch")
		(attr smd)
		(fp_rect
			(start -0.725 0.475)
			(end 0.725 -0.475)
			(stroke
				(width 0.05)
				(type solid)
			)
			(fill none)
			(layer "B.CrtYd")
		)
		(fp_rect
			(start -0.55 0.35)
			(end 0.55 -0.35)
			(stroke
				(width 0.15)
				(type solid)
			)
			(fill none)
			(layer "B.Fab")
		)
		(fp_text user "${REFERENCE}"
			(at -0.8 -3.2 180)
			(layer "B.Fab")
			(hide yes)
			(effects
				(font
					(size 0.7 0.7)
					(thickness 0.15)
				)
				(justify left bottom mirror)
			)
		)
		(fp_text user "Author: Antmicro"
			(at -0.8 -4.4 180)
			(layer "B.Fab")
			(hide yes)
			(effects
				(font
					(size 0.7 0.7)
					(thickness 0.15)
				)
				(justify left bottom mirror)
			)
		)
		(fp_text user "License: Apache-2.0"
			(at -0.8 -5.6 180)
			(layer "B.Fab")
			(hide yes)
			(effects
				(font
					(size 0.7 0.7)
					(thickness 0.15)
				)
				(justify left bottom mirror)
			)
		)
		(pad "1" smd roundrect
			(at -0.351 0)
			(size 0.3 0.5)
			(layers "B.Cu" "B.Paste" "B.Mask")
			(roundrect_rratio 0.25)
			(net 1 "GND")
			(pinfunction "C")
			(pintype "passive")
		)
		(pad "2" smd roundrect
			(at 0.349 0)
			(size 0.3 0.5)
			(layers "B.Cu" "B.Paste" "B.Mask")
			(roundrect_rratio 0.25)
			(net 46 "USER_BTN1")
			(pinfunction "A")
			(pintype "passive")
		)
	)
	(footprint "antmicro-footprints:Fiducial_1mm_Mask2mm"
		(layer "B.Cu")
		(at 148.2 76.25 180)
		(descr "Circular Fiducial, 1mm bare copper, 3mm soldermask opening")
		(tags "fiducial")
		(property "Reference" "FID7"
			(at 0 1.4 0)
			(layer "B.SilkS")
			(hide yes)
			(effects
				(font
					(size 0.7 0.7)
					(thickness 0.15)
				)
				(justify left bottom mirror)
			)
		)
		(property "Value" "Fiducial_1mm_Mask2mm"
			(at 0 -2.2 0)
			(layer "B.Fab")
			(effects
				(font
					(size 0.7 0.7)
					(thickness 0.15)
				)
				(justify left bottom mirror)
			)
		)
		(property "Footprint" "antmicro-footprints:Fiducial_1mm_Mask2mm"
			(at 0 0 180)
			(layer "F.Fab")
			(hide yes)
			(effects
				(font
					(size 1.27 1.27)
					(thickness 0.15)
				)
			)
		)
		(attr board_only exclude_from_pos_files exclude_from_bom)
		(fp_circle
			(center 0 0)
			(end 1.24 0)
			(stroke
				(width 0.05)
				(type solid)
			)
			(fill none)
			(layer "B.CrtYd")
		)
		(fp_circle
			(center 0 0)
			(end 0.999 0)
			(stroke
				(width 0.15)
				(type solid)
			)
			(fill none)
			(layer "B.Fab")
		)
		(fp_text user "Author: Antmicro"
			(at -1.25 -5.803 0)
			(layer "B.Fab")
			(hide yes)
			(effects
				(font
					(size 0.7 0.7)
					(thickness 0.15)
				)
				(justify left bottom mirror)
			)
		)
		(fp_text user "${REFERENCE}"
			(at -1.25 -4.603 0)
			(layer "B.Fab")
			(hide yes)
			(effects
				(font
					(size 0.7 0.7)
					(thickness 0.15)
				)
				(justify left bottom mirror)
			)
		)
		(fp_text user "License: Apache-2.0"
			(at -1.25 -7.003 0)
			(layer "B.Fab")
			(hide yes)
			(effects
				(font
					(size 0.7 0.7)
					(thickness 0.15)
				)
				(justify left bottom mirror)
			)
		)
		(pad "" smd circle
			(at 0 0 180)
			(size 1 1)
			(layers "B.Cu" "B.Mask")
			(solder_mask_margin 0.5)
			(clearance 0.5)
		)
	)
	(footprint "antmicro-footprints:C_2220_5650Metric"
		(layer "B.Cu")
		(at 34.1 95.525 180)
		(descr "Capacitor SMD 2220")
		(tags "capacitor SMD 2220")
		(property "Reference" "C80"
			(at -4.51 1.72 90)
			(layer "B.SilkS")
			(effects
				(font
					(size 0.7 0.7)
					(thickness 0.15)
				)
				(justify left bottom mirror)
			)
		)
		(property "Value" "C_22u_100V_2220"
			(at 0 -3.9 0)
			(layer "B.Fab")
			(effects
				(font
					(size 0.7 0.7)
					(thickness 0.15)
				)
				(justify left bottom mirror)
			)
		)
		(property "Footprint" "antmicro-footprints:C_2220_5650Metric"
			(at 0 0 180)
			(layer "F.Fab")
			(hide yes)
			(effects
				(font
					(size 1.27 1.27)
					(thickness 0.15)
				)
			)
		)
		(property "Datasheet" "https://product.tdk.com/en/search/capacitor/ceramic/mlcc/info?part_no=C5750X7S2A226M280KB"
			(at 0 0 180)
			(layer "F.Fab")
			(hide yes)
			(effects
				(font
					(size 1.27 1.27)
					(thickness 0.15)
				)
			)
		)
		(property "Author" "Antmicro"
			(at 68.2 191.05 0)
			(layer "B.Fab")
			(hide yes)
			(effects
				(font
					(size 1 1)
					(thickness 0.15)
				)
				(justify mirror)
			)
		)
		(property "Dielectric" "X7S"
			(at 68.2 191.05 0)
			(layer "B.Fab")
			(hide yes)
			(effects
				(font
					(size 1 1)
					(thickness 0.15)
				)
				(justify mirror)
			)
		)
		(property "License" "Apache-2.0"
			(at 68.2 191.05 0)
			(layer "B.Fab")
			(hide yes)
			(effects
				(font
					(size 1 1)
					(thickness 0.15)
				)
				(justify mirror)
			)
		)
		(property "MPN" "C5750X7S2A226M280KB"
			(at 68.2 191.05 0)
			(layer "B.Fab")
			(hide yes)
			(effects
				(font
					(size 1 1)
					(thickness 0.15)
				)
				(justify mirror)
			)
		)
		(property "Manufacturer" "TDK"
			(at 68.2 191.05 0)
			(layer "B.Fab")
			(hide yes)
			(effects
				(font
					(size 1 1)
					(thickness 0.15)
				)
				(justify mirror)
			)
		)
		(property "Public" "False"
			(at 68.2 191.05 0)
			(layer "B.Fab")
			(hide yes)
			(effects
				(font
					(size 1 1)
					(thickness 0.15)
				)
				(justify mirror)
			)
		)
		(property "Val" "22u"
			(at 68.2 191.05 0)
			(layer "B.Fab")
			(hide yes)
			(effects
				(font
					(size 1 1)
					(thickness 0.15)
				)
				(justify mirror)
			)
		)
		(property "Voltage" "100V"
			(at 68.2 191.05 0)
			(layer "B.Fab")
			(hide yes)
			(effects
				(font
					(size 1 1)
					(thickness 0.15)
				)
				(justify mirror)
			)
		)
		(sheetname "Ethernet")
		(sheetfile "ethernet.kicad_sch")
		(attr smd)
		(fp_line
			(start 1.415 2.61)
			(end -1.415 2.61)
			(stroke
				(width 0.15)
				(type solid)
			)
			(layer "B.SilkS")
		)
		(fp_line
			(start 1.415 -2.61)
			(end -1.415 -2.61)
			(stroke
				(width 0.15)
				(type solid)
			)
			(layer "B.SilkS")
		)
		(fp_rect
			(start -3.7 2.95)
			(end 3.7 -2.95)
			(stroke
				(width 0.05)
				(type solid)
			)
			(fill none)
			(layer "B.CrtYd")
		)
		(fp_rect
			(start -2.85 2.5)
			(end 2.85 -2.5)
			(stroke
				(width 0.15)
				(type solid)
			)
			(fill none)
			(layer "B.Fab")
		)
		(fp_text user "Author: Antmicro"
			(at -3.7 -7.9 0)
			(layer "B.Fab")
			(hide yes)
			(effects
				(font
					(size 0.7 0.7)
					(thickness 0.15)
				)
				(justify left bottom mirror)
			)
		)
		(fp_text user "License: Apache-2.0"
			(at -3.7 -6.9 0)
			(layer "B.Fab")
			(hide yes)
			(effects
				(font
					(size 0.7 0.7)
					(thickness 0.15)
				)
				(justify left bottom mirror)
			)
		)
		(fp_text user "${REFERENCE}"
			(at -3.7 -5.9 0)
			(layer "B.Fab")
			(hide yes)
			(effects
				(font
					(size 0.7 0.7)
					(thickness 0.15)
				)
				(justify left bottom mirror)
			)
		)
		(pad "1" smd roundrect
			(at -2.55 0 180)
			(size 1.8 5.4)
			(layers "B.Cu" "B.Paste" "B.Mask")
			(roundrect_rratio 0.138889)
			(net 106 "GNDD")
			(pintype "passive")
		)
		(pad "2" smd roundrect
			(at 2.55 0 180)
			(size 1.8 5.4)
			(layers "B.Cu" "B.Paste" "B.Mask")
			(roundrect_rratio 0.138889)
			(net 105 "/Ethernet/VDD")
			(pintype "passive")
		)
	)
	(footprint "antmicro-footprints:C_0402_1005Metric"
		(layer "B.Cu")
		(at 96.5 84.75)
		(descr "Capacitor SMD 0402")
		(tags "capacitor SMD 0402")
		(property "Reference" "C90"
			(at 1.16 1.21 180)
			(layer "B.SilkS")
			(effects
				(font
					(size 0.7 0.7)
					(thickness 0.15)
				)
				(justify left bottom mirror)
			)
		)
		(property "Value" "C_100n_0402"
			(at 0 -1.4 180)
			(layer "B.Fab")
			(effects
				(font
					(size 0.7 0.7)
					(thickness 0.15)
				)
				(justify left bottom mirror)
			)
		)
		(property "Footprint" "antmicro-footprints:C_0402_1005Metric"
			(at 0 0 0)
			(layer "F.Fab")
			(hide yes)
			(effects
				(font
					(size 1.27 1.27)
					(thickness 0.15)
				)
			)
		)
		(property "Datasheet" "https://www.murata.com/products/productdetail?partno=GRM155R61H104KE14%23"
			(at 0 0 0)
			(layer "F.Fab")
			(hide yes)
			(effects
				(font
					(size 1.27 1.27)
					(thickness 0.15)
				)
			)
		)
		(property "Author" "Antmicro"
			(at 0 0 0)
			(layer "B.Fab")
			(hide yes)
			(effects
				(font
					(size 1 1)
					(thickness 0.15)
				)
				(justify mirror)
			)
		)
		(property "Dielectric" "X5R"
			(at 0 0 0)
			(layer "B.Fab")
			(hide yes)
			(effects
				(font
					(size 1 1)
					(thickness 0.15)
				)
				(justify mirror)
			)
		)
		(property "License" "Apache-2.0"
			(at 0 0 0)
			(layer "B.Fab")
			(hide yes)
			(effects
				(font
					(size 1 1)
					(thickness 0.15)
				)
				(justify mirror)
			)
		)
		(property "MPN" "GRM155R61H104KE14D"
			(at 0 0 0)
			(layer "B.Fab")
			(hide yes)
			(effects
				(font
					(size 1 1)
					(thickness 0.15)
				)
				(justify mirror)
			)
		)
		(property "Manufacturer" "Murata"
			(at 0 0 0)
			(layer "B.Fab")
			(hide yes)
			(effects
				(font
					(size 1 1)
					(thickness 0.15)
				)
				(justify mirror)
			)
		)
		(property "Val" "100n"
			(at 0 0 0)
			(layer "B.Fab")
			(hide yes)
			(effects
				(font
					(size 1 1)
					(thickness 0.15)
				)
				(justify mirror)
			)
		)
		(property "Voltage" "50V"
			(at 0 0 0)
			(layer "B.Fab")
			(hide yes)
			(effects
				(font
					(size 1 1)
					(thickness 0.15)
				)
				(justify mirror)
			)
		)
		(sheetname "CSI")
		(sheetfile "csi.kicad_sch")
		(attr smd)
		(fp_rect
			(start -0.925 0.47)
			(end 0.925 -0.47)
			(stroke
				(width 0.05)
				(type default)
			)
			(fill none)
			(layer "B.CrtYd")
		)
		(fp_line
			(start -0.494 -0.248)
			(end 0.504 -0.248)
			(stroke
				(width 0.15)
				(type solid)
			)
			(layer "B.Fab")
		)
		(fp_line
			(start -0.494 0.25)
			(end -0.494 -0.248)
			(stroke
				(width 0.15)
				(type solid)
			)
			(layer "B.Fab")
		)
		(fp_line
			(start 0.504 -0.248)
			(end 0.504 0.25)
			(stroke
				(width 0.15)
				(type solid)
			)
			(layer "B.Fab")
		)
		(fp_line
			(start 0.504 0.25)
			(end -0.494 0.25)
			(stroke
				(width 0.15)
				(type solid)
			)
			(layer "B.Fab")
		)
		(fp_text user "Author: Antmicro"
			(at -0.932 -4.17 180)
			(layer "B.Fab")
			(hide yes)
			(effects
				(font
					(size 0.7 0.7)
					(thickness 0.15)
				)
				(justify left bottom mirror)
			)
		)
		(fp_text user "License: Apache-2.0"
			(at -0.932 -5.17 180)
			(layer "B.Fab")
			(hide yes)
			(effects
				(font
					(size 0.7 0.7)
					(thickness 0.15)
				)
				(justify left bottom mirror)
			)
		)
		(fp_text user "${REFERENCE}"
			(at -0.932 -3.168 180)
			(layer "B.Fab")
			(hide yes)
			(effects
				(font
					(size 0.7 0.7)
					(thickness 0.15)
				)
				(justify left bottom mirror)
			)
		)
		(pad "1" smd roundrect
			(at -0.48 0)
			(size 0.59 0.64)
			(layers "B.Cu" "B.Paste" "B.Mask")
			(roundrect_rratio 0.25)
			(net 99 "+5V")
			(pintype "passive")
		)
		(pad "2" smd roundrect
			(at 0.48 0)
			(size 0.59 0.64)
			(layers "B.Cu" "B.Paste" "B.Mask")
			(roundrect_rratio 0.25)
			(net 1 "GND")
			(pintype "passive")
		)
	)
)
